(kicad_pcb
	(version 20260206)
	(generator "pcbnew")
	(generator_version "10.0")
	(general
		(thickness 1.6)
		(legacy_teardrops no)
	)
	(paper "A4")
	(title_block
		(title "9054_F0T_PDB_BD_GPU_F_V04_1213_1550_OCP.brd")
		(comment 1 "Grand Teton / footprints 585-591 of 608")
	)
	(layers
		(0 "F.Cu" signal "TOP")
		(4 "In1.Cu" signal "GND")
		(6 "In2.Cu" signal "IN1")
		(8 "In3.Cu" signal "GND1")
		(10 "In4.Cu" signal "VCC")
		(12 "In5.Cu" signal "VCC1")
		(14 "In6.Cu" signal "GND2")
		(16 "In7.Cu" signal "IN2")
		(18 "In8.Cu" signal "GND3")
		(2 "B.Cu" signal "BOTTOM")
		(9 "F.Adhes" user "F.Adhesive")
		(11 "B.Adhes" user "B.Adhesive")
		(13 "F.Paste" user "Package Geometry/Pastemask Top")
		(15 "B.Paste" user "Package Geometry/Pastemask Bottom")
		(5 "F.SilkS" user "Ref Des/Silkscreen Top")
		(7 "B.SilkS" user "Ref Des/Silkscreen Bottom")
		(1 "F.Mask" user "Board Geometry/Soldermask Top")
		(3 "B.Mask" user "Board Geometry/Soldermask Bottom")
		(17 "Dwgs.User" user "User.Drawings")
		(19 "Cmts.User" user "User.Comments")
		(21 "Eco1.User" user "User.Eco1")
		(23 "Eco2.User" user "User.Eco2")
		(25 "Edge.Cuts" user "Board Geometry/Outline")
		(27 "Margin" user)
		(31 "F.CrtYd" user "Package Geometry/Place Bound Top")
		(29 "B.CrtYd" user "Package Geometry/Place Bound Bottom")
		(35 "F.Fab" user "Ref Des/Assembly Top")
		(33 "B.Fab" user "Ref Des/Assembly Bottom")
	)
	(footprint ""
		(layer "B.Cu")
		(at 341.5792 -38.7858 -90)
		(property "Reference" "PR6999"
			(at 0 0 90)
			(layer "B.SilkS")
			(hide yes)
			(effects
				(font
					(size 1.27 1.27)
				)
				(justify mirror)
			)
		)
		(property "Value" ""
			(at 0 0 90)
			(layer "B.Fab")
			(effects
				(font
					(size 1.27 1.27)
				)
				(justify mirror)
			)
		)
		(duplicate_pad_numbers_are_jumpers no)
		(fp_line
			(start -1.2954 0.5842)
			(end 1.2954 0.5842)
			(stroke
				(width 0.1524)
				(type default)
			)
			(layer "B.SilkS")
		)
		(fp_line
			(start 1.2954 0.5842)
			(end 1.2954 -0.5842)
			(stroke
				(width 0.1524)
				(type default)
			)
			(layer "B.SilkS")
		)
		(fp_line
			(start -1.2954 -0.5842)
			(end -1.2954 0.5842)
			(stroke
				(width 0.1524)
				(type default)
			)
			(layer "B.SilkS")
		)
		(fp_line
			(start 1.2954 -0.5842)
			(end -1.2954 -0.5842)
			(stroke
				(width 0.1524)
				(type default)
			)
			(layer "B.SilkS")
		)
		(fp_line
			(start -0.8636 0.4572)
			(end 0.8636 0.4572)
			(stroke
				(width 0.1)
				(type default)
			)
			(layer "B.Fab")
		)
		(fp_line
			(start 0.8636 0.4572)
			(end 0.8636 0.4318)
			(stroke
				(width 0.1)
				(type default)
			)
			(layer "B.Fab")
		)
		(fp_line
			(start 0.8636 0.4318)
			(end 0.8636 0.4064)
			(stroke
				(width 0.1)
				(type default)
			)
			(layer "B.Fab")
		)
		(fp_line
			(start -1.1938 0.4064)
			(end -0.8636 0.4064)
			(stroke
				(width 0.1)
				(type default)
			)
			(layer "B.Fab")
		)
		(fp_line
			(start -0.8636 0.4064)
			(end -0.8636 0.4572)
			(stroke
				(width 0.1)
				(type default)
			)
			(layer "B.Fab")
		)
		(fp_line
			(start 0.8636 0.4064)
			(end 1.1938 0.4064)
			(stroke
				(width 0.1)
				(type default)
			)
			(layer "B.Fab")
		)
		(fp_line
			(start 1.1938 0.4064)
			(end 1.1938 -0.406654)
			(stroke
				(width 0.1)
				(type default)
			)
			(layer "B.Fab")
		)
		(fp_line
			(start -1.1938 -0.406654)
			(end -1.1938 0.4064)
			(stroke
				(width 0.1)
				(type default)
			)
			(layer "B.Fab")
		)
		(fp_line
			(start -0.8636 -0.406654)
			(end -1.1938 -0.406654)
			(stroke
				(width 0.1)
				(type default)
			)
			(layer "B.Fab")
		)
		(fp_line
			(start 0.8636 -0.406654)
			(end 0.8636 -0.4572)
			(stroke
				(width 0.1)
				(type default)
			)
			(layer "B.Fab")
		)
		(fp_line
			(start 1.1938 -0.406654)
			(end 0.8636 -0.406654)
			(stroke
				(width 0.1)
				(type default)
			)
			(layer "B.Fab")
		)
		(fp_line
			(start -0.8636 -0.4572)
			(end -0.8636 -0.406654)
			(stroke
				(width 0.1)
				(type default)
			)
			(layer "B.Fab")
		)
		(fp_line
			(start 0.8636 -0.4572)
			(end -0.8636 -0.4572)
			(stroke
				(width 0.1)
				(type default)
			)
			(layer "B.Fab")
		)
		(pad "1" smd rect
			(at 0.7366 0 180)
			(size 0.7112 0.8128)
			(layers "B.Cu" "B.Mask" "B.Paste")
			(net "P52V_HS1_4287_GATE2_R")
		)
		(pad "2" smd rect
			(at -0.7366 0 180)
			(size 0.7112 0.8128)
			(layers "B.Cu" "B.Mask" "B.Paste")
			(net "P52V_HS1_4287_GATE2_RC")
		)
	)
	(footprint ""
		(layer "B.Cu")
		(at 278.4094 -65.913)
		(property "Reference" "R144"
			(at 0 0 0)
			(layer "B.SilkS")
			(hide yes)
			(effects
				(font
					(size 1.27 1.27)
				)
				(justify mirror)
			)
		)
		(property "Value" ""
			(at 0 0 0)
			(layer "B.Fab")
			(effects
				(font
					(size 1.27 1.27)
				)
				(justify mirror)
			)
		)
		(duplicate_pad_numbers_are_jumpers no)
		(fp_line
			(start -0.7874 -0.4064)
			(end -0.7874 0.4064)
			(stroke
				(width 0.1524)
				(type default)
			)
			(layer "B.SilkS")
		)
		(fp_line
			(start -0.7874 0.4064)
			(end 0.7874 0.4064)
			(stroke
				(width 0.1524)
				(type default)
			)
			(layer "B.SilkS")
		)
		(fp_line
			(start 0.7874 -0.4064)
			(end -0.7874 -0.4064)
			(stroke
				(width 0.1524)
				(type default)
			)
			(layer "B.SilkS")
		)
		(fp_line
			(start 0.7874 0.4064)
			(end 0.7874 -0.4064)
			(stroke
				(width 0.1524)
				(type default)
			)
			(layer "B.SilkS")
		)
		(fp_line
			(start -0.67945 -0.3048)
			(end -0.67945 0.3048)
			(stroke
				(width 0.1)
				(type default)
			)
			(layer "B.Fab")
		)
		(fp_line
			(start -0.67945 0.3048)
			(end -0.120396 0.3048)
			(stroke
				(width 0.1)
				(type default)
			)
			(layer "B.Fab")
		)
		(fp_line
			(start -0.12065 -0.3048)
			(end -0.67945 -0.3048)
			(stroke
				(width 0.1)
				(type default)
			)
			(layer "B.Fab")
		)
		(fp_line
			(start -0.12065 -0.2794)
			(end -0.12065 -0.3048)
			(stroke
				(width 0.1)
				(type default)
			)
			(layer "B.Fab")
		)
		(fp_line
			(start -0.120396 0.2794)
			(end 0.12065 0.2794)
			(stroke
				(width 0.1)
				(type default)
			)
			(layer "B.Fab")
		)
		(fp_line
			(start -0.120396 0.3048)
			(end -0.120396 0.2794)
			(stroke
				(width 0.1)
				(type default)
			)
			(layer "B.Fab")
		)
		(fp_line
			(start 0.12065 -0.305054)
			(end 0.12065 -0.2794)
			(stroke
				(width 0.1)
				(type default)
			)
			(layer "B.Fab")
		)
		(fp_line
			(start 0.12065 -0.2794)
			(end -0.12065 -0.2794)
			(stroke
				(width 0.1)
				(type default)
			)
			(layer "B.Fab")
		)
		(fp_line
			(start 0.12065 0.2794)
			(end 0.12065 0.3048)
			(stroke
				(width 0.1)
				(type default)
			)
			(layer "B.Fab")
		)
		(fp_line
			(start 0.12065 0.3048)
			(end 0.67945 0.3048)
			(stroke
				(width 0.1)
				(type default)
			)
			(layer "B.Fab")
		)
		(fp_line
			(start 0.67945 -0.305054)
			(end 0.12065 -0.305054)
			(stroke
				(width 0.1)
				(type default)
			)
			(layer "B.Fab")
		)
		(fp_line
			(start 0.67945 0.3048)
			(end 0.67945 -0.305054)
			(stroke
				(width 0.1)
				(type default)
			)
			(layer "B.Fab")
		)
		(pad "1" smd circle
			(at 0.40005 0 180)
			(size 0 0)
			(layers "B.Cu" "B.Mask" "B.Paste")
			(net "SMB_P52V_PDB_SDA")
		)
		(pad "2" smd circle
			(at -0.40005 0 180)
			(size 0 0)
			(layers "B.Cu" "B.Mask" "B.Paste")
			(net "SMB_CM_HS1_3V3SB_DATI")
		)
	)
	(footprint ""
		(layer "B.Cu")
		(at 287.6804 -68.58)
		(property "Reference" "PR212"
			(at 0 0 0)
			(layer "B.SilkS")
			(hide yes)
			(effects
				(font
					(size 1.27 1.27)
				)
				(justify mirror)
			)
		)
		(property "Value" ""
			(at 0 0 0)
			(layer "B.Fab")
			(effects
				(font
					(size 1.27 1.27)
				)
				(justify mirror)
			)
		)
		(duplicate_pad_numbers_are_jumpers no)
		(fp_line
			(start -0.7874 -0.4064)
			(end -0.7874 0.4064)
			(stroke
				(width 0.1524)
				(type default)
			)
			(layer "B.SilkS")
		)
		(fp_line
			(start -0.7874 0.4064)
			(end 0.7874 0.4064)
			(stroke
				(width 0.1524)
				(type default)
			)
			(layer "B.SilkS")
		)
		(fp_line
			(start 0.7874 -0.4064)
			(end -0.7874 -0.4064)
			(stroke
				(width 0.1524)
				(type default)
			)
			(layer "B.SilkS")
		)
		(fp_line
			(start 0.7874 0.4064)
			(end 0.7874 -0.4064)
			(stroke
				(width 0.1524)
				(type default)
			)
			(layer "B.SilkS")
		)
		(fp_line
			(start -0.67945 -0.3048)
			(end -0.67945 0.3048)
			(stroke
				(width 0.1)
				(type default)
			)
			(layer "B.Fab")
		)
		(fp_line
			(start -0.67945 0.3048)
			(end -0.120396 0.3048)
			(stroke
				(width 0.1)
				(type default)
			)
			(layer "B.Fab")
		)
		(fp_line
			(start -0.12065 -0.3048)
			(end -0.67945 -0.3048)
			(stroke
				(width 0.1)
				(type default)
			)
			(layer "B.Fab")
		)
		(fp_line
			(start -0.12065 -0.2794)
			(end -0.12065 -0.3048)
			(stroke
				(width 0.1)
				(type default)
			)
			(layer "B.Fab")
		)
		(fp_line
			(start -0.120396 0.2794)
			(end 0.12065 0.2794)
			(stroke
				(width 0.1)
				(type default)
			)
			(layer "B.Fab")
		)
		(fp_line
			(start -0.120396 0.3048)
			(end -0.120396 0.2794)
			(stroke
				(width 0.1)
				(type default)
			)
			(layer "B.Fab")
		)
		(fp_line
			(start 0.12065 -0.305054)
			(end 0.12065 -0.2794)
			(stroke
				(width 0.1)
				(type default)
			)
			(layer "B.Fab")
		)
		(fp_line
			(start 0.12065 -0.2794)
			(end -0.12065 -0.2794)
			(stroke
				(width 0.1)
				(type default)
			)
			(layer "B.Fab")
		)
		(fp_line
			(start 0.12065 0.2794)
			(end 0.12065 0.3048)
			(stroke
				(width 0.1)
				(type default)
			)
			(layer "B.Fab")
		)
		(fp_line
			(start 0.12065 0.3048)
			(end 0.67945 0.3048)
			(stroke
				(width 0.1)
				(type default)
			)
			(layer "B.Fab")
		)
		(fp_line
			(start 0.67945 -0.305054)
			(end 0.12065 -0.305054)
			(stroke
				(width 0.1)
				(type default)
			)
			(layer "B.Fab")
		)
		(fp_line
			(start 0.67945 0.3048)
			(end 0.67945 -0.305054)
			(stroke
				(width 0.1)
				(type default)
			)
			(layer "B.Fab")
		)
		(pad "1" smd circle
			(at 0.40005 0 180)
			(size 0 0)
			(layers "B.Cu" "B.Mask" "B.Paste")
			(net "P52V_HS1_SIO")
		)
		(pad "2" smd circle
			(at -0.40005 0 180)
			(size 0 0)
			(layers "B.Cu" "B.Mask" "B.Paste")
			(net "P52V_HS1_INTVCC")
		)
	)
	(footprint ""
		(layer "B.Cu")
		(at 293.2684 -80.01 -90)
		(property "Reference" "PJ1"
			(at -0.254 -1.34493 270)
			(unlocked yes)
			(layer "B.SilkS")
			(effects
				(font
					(size 0.7874 0.5842)
					(thickness 0.1524)
				)
				(justify left mirror)
			)
		)
		(property "Value" ""
			(at 0 0 90)
			(layer "B.Fab")
			(effects
				(font
					(size 1.27 1.27)
				)
				(justify mirror)
			)
		)
		(duplicate_pad_numbers_are_jumpers no)
		(pad "1" smd circle
			(at 0.7493 0)
			(size 0 0)
			(layers "B.Cu" "B.Mask" "B.Paste")
			(net "GND_FIELD_SIGNAL")
		)
		(pad "2" smd rect
			(at -0.7493 0 180)
			(size 0.7112 0.8128)
			(layers "B.Cu" "B.Mask" "B.Paste")
			(net "GND")
		)
		(zone
			(layer "B.Cu")
			(hatch none 0.5)
			(connect_pads
				(clearance 0)
			)
			(min_thickness 0.25)
			(keepout
				(tracks allowed)
				(vias not_allowed)
				(pads allowed)
				(copperpour not_allowed)
				(footprints allowed)
			)
			(placement
				(enabled no)
				(sheetname "")
			)
			(fill
				(thermal_gap 0.5)
				(thermal_bridge_width 0.5)
				(island_removal_mode 0)
			)
			(polygon
				(pts
					(xy 293.6748 -81.2165) (xy 292.857174 -81.2165) (xy 292.857174 -78.8289) (xy 293.6748 -78.8289)
				)
			)
		)
	)
	(footprint ""
		(layer "B.Cu")
		(at 106.1974 -57.023 180)
		(property "Reference" "PC592"
			(at 0 0 0)
			(layer "B.SilkS")
			(hide yes)
			(effects
				(font
					(size 1.27 1.27)
				)
				(justify mirror)
			)
		)
		(property "Value" ""
			(at 0 0 0)
			(layer "B.Fab")
			(effects
				(font
					(size 1.27 1.27)
				)
				(justify mirror)
			)
		)
		(duplicate_pad_numbers_are_jumpers no)
		(fp_line
			(start 1.2954 0.5842)
			(end 1.2954 -0.5842)
			(stroke
				(width 0.1524)
				(type default)
			)
			(layer "B.SilkS")
		)
		(fp_line
			(start 1.2954 -0.5842)
			(end -1.2954 -0.5842)
			(stroke
				(width 0.1524)
				(type default)
			)
			(layer "B.SilkS")
		)
		(fp_line
			(start -1.2954 0.5842)
			(end 1.2954 0.5842)
			(stroke
				(width 0.1524)
				(type default)
			)
			(layer "B.SilkS")
		)
		(fp_line
			(start -1.2954 -0.5842)
			(end -1.2954 0.5842)
			(stroke
				(width 0.1524)
				(type default)
			)
			(layer "B.SilkS")
		)
		(fp_line
			(start 1.1938 0.4064)
			(end 1.1938 -0.4064)
			(stroke
				(width 0.1)
				(type default)
			)
			(layer "B.Fab")
		)
		(fp_line
			(start 1.1938 -0.4064)
			(end 0.8636 -0.4064)
			(stroke
				(width 0.1)
				(type default)
			)
			(layer "B.Fab")
		)
		(fp_line
			(start 0.8636 0.4572)
			(end 0.8636 0.4064)
			(stroke
				(width 0.1)
				(type default)
			)
			(layer "B.Fab")
		)
		(fp_line
			(start 0.8636 0.4064)
			(end 1.1938 0.4064)
			(stroke
				(width 0.1)
				(type default)
			)
			(layer "B.Fab")
		)
		(fp_line
			(start 0.8636 -0.4064)
			(end 0.8636 -0.4572)
			(stroke
				(width 0.1)
				(type default)
			)
			(layer "B.Fab")
		)
		(fp_line
			(start 0.8636 -0.4572)
			(end -0.8636 -0.4572)
			(stroke
				(width 0.1)
				(type default)
			)
			(layer "B.Fab")
		)
		(fp_line
			(start -0.8636 0.4572)
			(end 0.8636 0.4572)
			(stroke
				(width 0.1)
				(type default)
			)
			(layer "B.Fab")
		)
		(fp_line
			(start -0.8636 0.4064)
			(end -0.8636 0.4572)
			(stroke
				(width 0.1)
				(type default)
			)
			(layer "B.Fab")
		)
		(fp_line
			(start -0.8636 -0.4064)
			(end -1.1938 -0.4064)
			(stroke
				(width 0.1)
				(type default)
			)
			(layer "B.Fab")
		)
		(fp_line
			(start -0.8636 -0.4572)
			(end -0.8636 -0.4064)
			(stroke
				(width 0.1)
				(type default)
			)
			(layer "B.Fab")
		)
		(fp_line
			(start -1.1938 0.4064)
			(end -0.8636 0.4064)
			(stroke
				(width 0.1)
				(type default)
			)
			(layer "B.Fab")
		)
		(fp_line
			(start -1.1938 -0.4064)
			(end -1.1938 0.4064)
			(stroke
				(width 0.1)
				(type default)
			)
			(layer "B.Fab")
		)
		(pad "1" smd rect
			(at 0.7366 0 90)
			(size 0.7112 0.8128)
			(layers "B.Cu" "B.Mask" "B.Paste")
			(net "GND")
		)
		(pad "2" smd rect
			(at -0.7366 0 90)
			(size 0.7112 0.8128)
			(layers "B.Cu" "B.Mask" "B.Paste")
			(net "P52V_HS2_GATE_R1")
		)
	)
	(footprint ""
		(layer "B.Cu")
		(at 111.2774 -55.626 90)
		(property "Reference" "R5866"
			(at 0 0 90)
			(layer "B.SilkS")
			(hide yes)
			(effects
				(font
					(size 1.27 1.27)
				)
				(justify mirror)
			)
		)
		(property "Value" ""
			(at 0 0 90)
			(layer "B.Fab")
			(effects
				(font
					(size 1.27 1.27)
				)
				(justify mirror)
			)
		)
		(duplicate_pad_numbers_are_jumpers no)
		(fp_line
			(start 0.7874 -0.4064)
			(end -0.7874 -0.4064)
			(stroke
				(width 0.1524)
				(type default)
			)
			(layer "B.SilkS")
		)
		(fp_line
			(start -0.7874 -0.4064)
			(end -0.7874 0.4064)
			(stroke
				(width 0.1524)
				(type default)
			)
			(layer "B.SilkS")
		)
		(fp_line
			(start 0.7874 0.4064)
			(end 0.7874 -0.4064)
			(stroke
				(width 0.1524)
				(type default)
			)
			(layer "B.SilkS")
		)
		(fp_line
			(start -0.7874 0.4064)
			(end 0.7874 0.4064)
			(stroke
				(width 0.1524)
				(type default)
			)
			(layer "B.SilkS")
		)
		(fp_line
			(start 0.67945 -0.305054)
			(end 0.12065 -0.305054)
			(stroke
				(width 0.1)
				(type default)
			)
			(layer "B.Fab")
		)
		(fp_line
			(start 0.12065 -0.305054)
			(end 0.12065 -0.2794)
			(stroke
				(width 0.1)
				(type default)
			)
			(layer "B.Fab")
		)
		(fp_line
			(start -0.12065 -0.3048)
			(end -0.67945 -0.3048)
			(stroke
				(width 0.1)
				(type default)
			)
			(layer "B.Fab")
		)
		(fp_line
			(start -0.67945 -0.3048)
			(end -0.67945 0.3048)
			(stroke
				(width 0.1)
				(type default)
			)
			(layer "B.Fab")
		)
		(fp_line
			(start 0.12065 -0.2794)
			(end -0.12065 -0.2794)
			(stroke
				(width 0.1)
				(type default)
			)
			(layer "B.Fab")
		)
		(fp_line
			(start -0.12065 -0.2794)
			(end -0.12065 -0.3048)
			(stroke
				(width 0.1)
				(type default)
			)
			(layer "B.Fab")
		)
		(fp_line
			(start 0.12065 0.2794)
			(end 0.12065 0.3048)
			(stroke
				(width 0.1)
				(type default)
			)
			(layer "B.Fab")
		)
		(fp_line
			(start -0.120396 0.2794)
			(end 0.12065 0.2794)
			(stroke
				(width 0.1)
				(type default)
			)
			(layer "B.Fab")
		)
		(fp_line
			(start 0.67945 0.3048)
			(end 0.67945 -0.305054)
			(stroke
				(width 0.1)
				(type default)
			)
			(layer "B.Fab")
		)
		(fp_line
			(start 0.12065 0.3048)
			(end 0.67945 0.3048)
			(stroke
				(width 0.1)
				(type default)
			)
			(layer "B.Fab")
		)
		(fp_line
			(start -0.120396 0.3048)
			(end -0.120396 0.2794)
			(stroke
				(width 0.1)
				(type default)
			)
			(layer "B.Fab")
		)
		(fp_line
			(start -0.67945 0.3048)
			(end -0.120396 0.3048)
			(stroke
				(width 0.1)
				(type default)
			)
			(layer "B.Fab")
		)
		(pad "1" smd circle
			(at 0.40005 0 270)
			(size 0 0)
			(layers "B.Cu" "B.Mask" "B.Paste")
			(net "P52V_HS2_GATE1_R")
		)
		(pad "2" smd circle
			(at -0.40005 0 270)
			(size 0 0)
			(layers "B.Cu" "B.Mask" "B.Paste")
			(net "P52V_HS2_1272_GATE")
		)
	)
	(footprint ""
		(layer "B.Cu")
		(at 151.7904 -59.69 180)
		(property "Reference" "PR7005"
			(at 0 0 0)
			(layer "B.SilkS")
			(hide yes)
			(effects
				(font
					(size 1.27 1.27)
				)
				(justify mirror)
			)
		)
		(property "Value" ""
			(at 0 0 0)
			(layer "B.Fab")
			(effects
				(font
					(size 1.27 1.27)
				)
				(justify mirror)
			)
		)
		(duplicate_pad_numbers_are_jumpers no)
		(fp_line
			(start 1.651 0.8382)
			(end 1.651 -0.8382)
			(stroke
				(width 0.1524)
				(type default)
			)
			(layer "B.SilkS")
		)
		(fp_line
			(start 1.651 -0.8382)
			(end -1.651 -0.8382)
			(stroke
				(width 0.1524)
				(type default)
			)
			(layer "B.SilkS")
		)
		(fp_line
			(start -1.651 0.8382)
			(end 1.651 0.8382)
			(stroke
				(width 0.1524)
				(type default)
			)
			(layer "B.SilkS")
		)
		(fp_line
			(start -1.651 -0.8382)
			(end -1.651 0.8382)
			(stroke
				(width 0.1524)
				(type default)
			)
			(layer "B.SilkS")
		)
		(fp_line
			(start 1.559814 0.7366)
			(end 1.524 0.7366)
			(stroke
				(width 0.1)
				(type default)
			)
			(layer "B.Fab")
		)
		(fp_line
			(start 1.559814 -0.7366)
			(end 1.559814 0.7366)
			(stroke
				(width 0.1)
				(type default)
			)
			(layer "B.Fab")
		)
		(fp_line
			(start 1.524 0.7366)
			(end -1.524 0.7366)
			(stroke
				(width 0.1)
				(type default)
			)
			(layer "B.Fab")
		)
		(fp_line
			(start 1.524 -0.7366)
			(end 1.559814 -0.7366)
			(stroke
				(width 0.1)
				(type default)
			)
			(layer "B.Fab")
		)
		(fp_line
			(start -1.524 0.7366)
			(end -1.560576 0.7366)
			(stroke
				(width 0.1)
				(type default)
			)
			(layer "B.Fab")
		)
		(fp_line
			(start -1.524 -0.7366)
			(end 1.524 -0.7366)
			(stroke
				(width 0.1)
				(type default)
			)
			(layer "B.Fab")
		)
		(fp_line
			(start -1.560576 0.7366)
			(end -1.560576 -0.7366)
			(stroke
				(width 0.1)
				(type default)
			)
			(layer "B.Fab")
		)
		(fp_line
			(start -1.560576 -0.7366)
			(end -1.524 -0.7366)
			(stroke
				(width 0.1)
				(type default)
			)
			(layer "B.Fab")
		)
		(pad "1" smd rect
			(at 0.94996 0 180)
			(size 1.1176 1.3716)
			(layers "B.Cu" "B.Mask" "B.Paste")
			(net "P52V_HS2")
		)
		(pad "2" smd rect
			(at -0.94996 0 180)
			(size 1.1176 1.3716)
			(layers "B.Cu" "B.Mask" "B.Paste")
			(net "P52V_HS2_FB")
		)
	)
)
